(kicad_pcb
	(version 20260206)
	(generator "pcbnew")
	(generator_version "10.0")
	(general
		(thickness 1.6)
		(legacy_teardrops no)
	)
	(paper "A4")
	(title_block
		(title "9054_F0T_PDB_BD_GPU_F_V04_1213_1550_OCP.brd")
		(comment 1 "Grand Teton / footprints 190-196 of 608")
	)
	(layers
		(0 "F.Cu" signal "TOP")
		(4 "In1.Cu" signal "GND")
		(6 "In2.Cu" signal "IN1")
		(8 "In3.Cu" signal "GND1")
		(10 "In4.Cu" signal "VCC")
		(12 "In5.Cu" signal "VCC1")
		(14 "In6.Cu" signal "GND2")
		(16 "In7.Cu" signal "IN2")
		(18 "In8.Cu" signal "GND3")
		(2 "B.Cu" signal "BOTTOM")
		(9 "F.Adhes" user "F.Adhesive")
		(11 "B.Adhes" user "B.Adhesive")
		(13 "F.Paste" user "Package Geometry/Pastemask Top")
		(15 "B.Paste" user "Package Geometry/Pastemask Bottom")
		(5 "F.SilkS" user "Ref Des/Silkscreen Top")
		(7 "B.SilkS" user "Ref Des/Silkscreen Bottom")
		(1 "F.Mask" user "Board Geometry/Soldermask Top")
		(3 "B.Mask" user "Board Geometry/Soldermask Bottom")
		(17 "Dwgs.User" user "User.Drawings")
		(19 "Cmts.User" user "User.Comments")
		(21 "Eco1.User" user "User.Eco1")
		(23 "Eco2.User" user "User.Eco2")
		(25 "Edge.Cuts" user "Board Geometry/Outline")
		(27 "Margin" user)
		(31 "F.CrtYd" user "Package Geometry/Place Bound Top")
		(29 "B.CrtYd" user "Package Geometry/Place Bound Bottom")
		(35 "F.Fab" user "Ref Des/Assembly Top")
		(33 "B.Fab" user "Ref Des/Assembly Bottom")
	)
	(footprint ""
		(layer "F.Cu")
		(at 445.741806 -88.932258 180)
		(property "Reference" "PC57"
			(at 0 0 180)
			(layer "F.SilkS")
			(hide yes)
			(effects
				(font
					(size 1.27 1.27)
				)
			)
		)
		(property "Value" ""
			(at 0 0 180)
			(layer "F.Fab")
			(effects
				(font
					(size 1.27 1.27)
				)
			)
		)
		(duplicate_pad_numbers_are_jumpers no)
		(fp_line
			(start 1.524 0.762)
			(end -1.524 0.762)
			(stroke
				(width 0.1524)
				(type default)
			)
			(layer "F.SilkS")
		)
		(fp_line
			(start 1.524 -0.762)
			(end 1.524 0.762)
			(stroke
				(width 0.1524)
				(type default)
			)
			(layer "F.SilkS")
		)
		(fp_line
			(start -1.524 0.762)
			(end -1.524 -0.762)
			(stroke
				(width 0.1524)
				(type default)
			)
			(layer "F.SilkS")
		)
		(fp_line
			(start -1.524 -0.762)
			(end 1.524 -0.762)
			(stroke
				(width 0.1524)
				(type default)
			)
			(layer "F.SilkS")
		)
		(fp_line
			(start 1.1049 0.724916)
			(end 1.1049 -0.724916)
			(stroke
				(width 0.1)
				(type default)
			)
			(layer "F.Fab")
		)
		(fp_line
			(start 1.1049 -0.724916)
			(end -1.1049 -0.724916)
			(stroke
				(width 0.1)
				(type default)
			)
			(layer "F.Fab")
		)
		(fp_line
			(start -1.1049 0.724916)
			(end 1.1049 0.724916)
			(stroke
				(width 0.1)
				(type default)
			)
			(layer "F.Fab")
		)
		(fp_line
			(start -1.1049 -0.724916)
			(end -1.1049 0.724916)
			(stroke
				(width 0.1)
				(type default)
			)
			(layer "F.Fab")
		)
		(pad "1" smd rect
			(at -0.889 0)
			(size 1.016 1.27)
			(layers "F.Cu" "F.Mask" "F.Paste")
			(net "SW_P3V3_HPDB_FLT")
		)
		(pad "2" smd rect
			(at 0.889 0)
			(size 1.016 1.27)
			(layers "F.Cu" "F.Mask" "F.Paste")
			(net "GND")
		)
	)
	(footprint ""
		(layer "F.Cu")
		(at 112.988852 -77.9272 -90)
		(property "Reference" "PR6970"
			(at 0 0 270)
			(layer "F.SilkS")
			(hide yes)
			(effects
				(font
					(size 1.27 1.27)
				)
			)
		)
		(property "Value" ""
			(at 0 0 270)
			(layer "F.Fab")
			(effects
				(font
					(size 1.27 1.27)
				)
			)
		)
		(duplicate_pad_numbers_are_jumpers no)
		(fp_line
			(start -1.2954 0.5842)
			(end -1.2954 -0.5842)
			(stroke
				(width 0.1524)
				(type default)
			)
			(layer "F.SilkS")
		)
		(fp_line
			(start 1.2954 0.5842)
			(end -1.2954 0.5842)
			(stroke
				(width 0.1524)
				(type default)
			)
			(layer "F.SilkS")
		)
		(fp_line
			(start -1.2954 -0.5842)
			(end 1.2954 -0.5842)
			(stroke
				(width 0.1524)
				(type default)
			)
			(layer "F.SilkS")
		)
		(fp_line
			(start 1.2954 -0.5842)
			(end 1.2954 0.5842)
			(stroke
				(width 0.1524)
				(type default)
			)
			(layer "F.SilkS")
		)
		(fp_line
			(start -0.8636 0.4572)
			(end -0.8636 0.4318)
			(stroke
				(width 0.1)
				(type default)
			)
			(layer "F.Fab")
		)
		(fp_line
			(start 0.8636 0.4572)
			(end -0.8636 0.4572)
			(stroke
				(width 0.1)
				(type default)
			)
			(layer "F.Fab")
		)
		(fp_line
			(start -0.8636 0.4318)
			(end -0.8636 0.4064)
			(stroke
				(width 0.1)
				(type default)
			)
			(layer "F.Fab")
		)
		(fp_line
			(start -1.1938 0.4064)
			(end -1.1938 -0.406654)
			(stroke
				(width 0.1)
				(type default)
			)
			(layer "F.Fab")
		)
		(fp_line
			(start -0.8636 0.4064)
			(end -1.1938 0.4064)
			(stroke
				(width 0.1)
				(type default)
			)
			(layer "F.Fab")
		)
		(fp_line
			(start 0.8636 0.4064)
			(end 0.8636 0.4572)
			(stroke
				(width 0.1)
				(type default)
			)
			(layer "F.Fab")
		)
		(fp_line
			(start 1.1938 0.4064)
			(end 0.8636 0.4064)
			(stroke
				(width 0.1)
				(type default)
			)
			(layer "F.Fab")
		)
		(fp_line
			(start -1.1938 -0.406654)
			(end -0.8636 -0.406654)
			(stroke
				(width 0.1)
				(type default)
			)
			(layer "F.Fab")
		)
		(fp_line
			(start -0.8636 -0.406654)
			(end -0.8636 -0.4572)
			(stroke
				(width 0.1)
				(type default)
			)
			(layer "F.Fab")
		)
		(fp_line
			(start 0.8636 -0.406654)
			(end 1.1938 -0.406654)
			(stroke
				(width 0.1)
				(type default)
			)
			(layer "F.Fab")
		)
		(fp_line
			(start 1.1938 -0.406654)
			(end 1.1938 0.4064)
			(stroke
				(width 0.1)
				(type default)
			)
			(layer "F.Fab")
		)
		(fp_line
			(start -0.8636 -0.4572)
			(end 0.8636 -0.4572)
			(stroke
				(width 0.1)
				(type default)
			)
			(layer "F.Fab")
		)
		(fp_line
			(start 0.8636 -0.4572)
			(end 0.8636 -0.406654)
			(stroke
				(width 0.1)
				(type default)
			)
			(layer "F.Fab")
		)
		(pad "1" smd rect
			(at -0.7366 0 180)
			(size 0.7112 0.8128)
			(layers "F.Cu" "F.Mask" "F.Paste")
			(net "P52V_HS2_GATE1_R")
		)
		(pad "2" smd rect
			(at 0.7366 0 180)
			(size 0.7112 0.8128)
			(layers "F.Cu" "F.Mask" "F.Paste")
			(net "P52V_HS2_GATE1")
		)
	)
	(footprint ""
		(layer "F.Cu")
		(at 278.6634 -74.041 180)
		(property "Reference" "R371"
			(at 0 0 180)
			(layer "F.SilkS")
			(hide yes)
			(effects
				(font
					(size 1.27 1.27)
				)
			)
		)
		(property "Value" ""
			(at 0 0 180)
			(layer "F.Fab")
			(effects
				(font
					(size 1.27 1.27)
				)
			)
		)
		(duplicate_pad_numbers_are_jumpers no)
		(fp_line
			(start 0.7874 0.4064)
			(end -0.7874 0.4064)
			(stroke
				(width 0.1524)
				(type default)
			)
			(layer "F.SilkS")
		)
		(fp_line
			(start 0.7874 -0.4064)
			(end 0.7874 0.4064)
			(stroke
				(width 0.1524)
				(type default)
			)
			(layer "F.SilkS")
		)
		(fp_line
			(start -0.7874 0.4064)
			(end -0.7874 -0.4064)
			(stroke
				(width 0.1524)
				(type default)
			)
			(layer "F.SilkS")
		)
		(fp_line
			(start -0.7874 -0.4064)
			(end 0.7874 -0.4064)
			(stroke
				(width 0.1524)
				(type default)
			)
			(layer "F.SilkS")
		)
		(fp_line
			(start 0.67945 0.3048)
			(end 0.120396 0.3048)
			(stroke
				(width 0.1)
				(type default)
			)
			(layer "F.Fab")
		)
		(fp_line
			(start 0.67945 -0.3048)
			(end 0.67945 0.3048)
			(stroke
				(width 0.1)
				(type default)
			)
			(layer "F.Fab")
		)
		(fp_line
			(start 0.12065 -0.2794)
			(end 0.12065 -0.3048)
			(stroke
				(width 0.1)
				(type default)
			)
			(layer "F.Fab")
		)
		(fp_line
			(start 0.12065 -0.3048)
			(end 0.67945 -0.3048)
			(stroke
				(width 0.1)
				(type default)
			)
			(layer "F.Fab")
		)
		(fp_line
			(start 0.120396 0.3048)
			(end 0.120396 0.2794)
			(stroke
				(width 0.1)
				(type default)
			)
			(layer "F.Fab")
		)
		(fp_line
			(start 0.120396 0.2794)
			(end -0.12065 0.2794)
			(stroke
				(width 0.1)
				(type default)
			)
			(layer "F.Fab")
		)
		(fp_line
			(start -0.12065 0.3048)
			(end -0.67945 0.3048)
			(stroke
				(width 0.1)
				(type default)
			)
			(layer "F.Fab")
		)
		(fp_line
			(start -0.12065 0.2794)
			(end -0.12065 0.3048)
			(stroke
				(width 0.1)
				(type default)
			)
			(layer "F.Fab")
		)
		(fp_line
			(start -0.12065 -0.2794)
			(end 0.12065 -0.2794)
			(stroke
				(width 0.1)
				(type default)
			)
			(layer "F.Fab")
		)
		(fp_line
			(start -0.12065 -0.305054)
			(end -0.12065 -0.2794)
			(stroke
				(width 0.1)
				(type default)
			)
			(layer "F.Fab")
		)
		(fp_line
			(start -0.67945 0.3048)
			(end -0.67945 -0.305054)
			(stroke
				(width 0.1)
				(type default)
			)
			(layer "F.Fab")
		)
		(fp_line
			(start -0.67945 -0.305054)
			(end -0.12065 -0.305054)
			(stroke
				(width 0.1)
				(type default)
			)
			(layer "F.Fab")
		)
		(pad "1" smd circle
			(at -0.40005 0 180)
			(size 0 0)
			(layers "F.Cu" "F.Mask" "F.Paste")
			(net "P52V_HS1_VCAP")
		)
		(pad "2" smd circle
			(at 0.40005 0 180)
			(size 0 0)
			(layers "F.Cu" "F.Mask" "F.Paste")
			(net "P52V_HS1_ADR0")
		)
	)
	(footprint ""
		(layer "F.Cu")
		(at 438.023 -45.593)
		(property "Reference" "R383"
			(at 0 0 0)
			(layer "F.SilkS")
			(hide yes)
			(effects
				(font
					(size 1.27 1.27)
				)
			)
		)
		(property "Value" ""
			(at 0 0 0)
			(layer "F.Fab")
			(effects
				(font
					(size 1.27 1.27)
				)
			)
		)
		(duplicate_pad_numbers_are_jumpers no)
		(fp_line
			(start -0.7874 -0.4064)
			(end 0.7874 -0.4064)
			(stroke
				(width 0.1524)
				(type default)
			)
			(layer "F.SilkS")
		)
		(fp_line
			(start -0.7874 0.4064)
			(end -0.7874 -0.4064)
			(stroke
				(width 0.1524)
				(type default)
			)
			(layer "F.SilkS")
		)
		(fp_line
			(start 0.7874 -0.4064)
			(end 0.7874 0.4064)
			(stroke
				(width 0.1524)
				(type default)
			)
			(layer "F.SilkS")
		)
		(fp_line
			(start 0.7874 0.4064)
			(end -0.7874 0.4064)
			(stroke
				(width 0.1524)
				(type default)
			)
			(layer "F.SilkS")
		)
		(fp_line
			(start -0.67945 -0.305054)
			(end -0.12065 -0.305054)
			(stroke
				(width 0.1)
				(type default)
			)
			(layer "F.Fab")
		)
		(fp_line
			(start -0.67945 0.3048)
			(end -0.67945 -0.305054)
			(stroke
				(width 0.1)
				(type default)
			)
			(layer "F.Fab")
		)
		(fp_line
			(start -0.12065 -0.305054)
			(end -0.12065 -0.2794)
			(stroke
				(width 0.1)
				(type default)
			)
			(layer "F.Fab")
		)
		(fp_line
			(start -0.12065 -0.2794)
			(end 0.12065 -0.2794)
			(stroke
				(width 0.1)
				(type default)
			)
			(layer "F.Fab")
		)
		(fp_line
			(start -0.12065 0.2794)
			(end -0.12065 0.3048)
			(stroke
				(width 0.1)
				(type default)
			)
			(layer "F.Fab")
		)
		(fp_line
			(start -0.12065 0.3048)
			(end -0.67945 0.3048)
			(stroke
				(width 0.1)
				(type default)
			)
			(layer "F.Fab")
		)
		(fp_line
			(start 0.120396 0.2794)
			(end -0.12065 0.2794)
			(stroke
				(width 0.1)
				(type default)
			)
			(layer "F.Fab")
		)
		(fp_line
			(start 0.120396 0.3048)
			(end 0.120396 0.2794)
			(stroke
				(width 0.1)
				(type default)
			)
			(layer "F.Fab")
		)
		(fp_line
			(start 0.12065 -0.3048)
			(end 0.67945 -0.3048)
			(stroke
				(width 0.1)
				(type default)
			)
			(layer "F.Fab")
		)
		(fp_line
			(start 0.12065 -0.2794)
			(end 0.12065 -0.3048)
			(stroke
				(width 0.1)
				(type default)
			)
			(layer "F.Fab")
		)
		(fp_line
			(start 0.67945 -0.3048)
			(end 0.67945 0.3048)
			(stroke
				(width 0.1)
				(type default)
			)
			(layer "F.Fab")
		)
		(fp_line
			(start 0.67945 0.3048)
			(end 0.120396 0.3048)
			(stroke
				(width 0.1)
				(type default)
			)
			(layer "F.Fab")
		)
		(pad "1" smd circle
			(at -0.40005 0)
			(size 0 0)
			(layers "F.Cu" "F.Mask" "F.Paste")
			(net "GND")
		)
		(pad "2" smd circle
			(at 0.40005 0)
			(size 0 0)
			(layers "F.Cu" "F.Mask" "F.Paste")
			(net "GPU_HSC_EN")
		)
	)
	(footprint ""
		(layer "F.Cu")
		(at 428.0154 -31.3436 -90)
		(property "Reference" "C9"
			(at 0 0 270)
			(layer "F.SilkS")
			(hide yes)
			(effects
				(font
					(size 1.27 1.27)
				)
			)
		)
		(property "Value" ""
			(at 0 0 270)
			(layer "F.Fab")
			(effects
				(font
					(size 1.27 1.27)
				)
			)
		)
		(duplicate_pad_numbers_are_jumpers no)
		(fp_line
			(start -0.7874 0.4064)
			(end -0.7874 -0.4064)
			(stroke
				(width 0.1524)
				(type default)
			)
			(layer "F.SilkS")
		)
		(fp_line
			(start 0.7874 0.4064)
			(end -0.7874 0.4064)
			(stroke
				(width 0.1524)
				(type default)
			)
			(layer "F.SilkS")
		)
		(fp_line
			(start -0.7874 -0.4064)
			(end 0.7874 -0.4064)
			(stroke
				(width 0.1524)
				(type default)
			)
			(layer "F.SilkS")
		)
		(fp_line
			(start 0.7874 -0.4064)
			(end 0.7874 0.4064)
			(stroke
				(width 0.1524)
				(type default)
			)
			(layer "F.SilkS")
		)
		(fp_line
			(start -0.67945 0.3048)
			(end -0.67945 -0.305054)
			(stroke
				(width 0.1)
				(type default)
			)
			(layer "F.Fab")
		)
		(fp_line
			(start -0.12065 0.3048)
			(end -0.67945 0.3048)
			(stroke
				(width 0.1)
				(type default)
			)
			(layer "F.Fab")
		)
		(fp_line
			(start 0.120396 0.3048)
			(end 0.120396 0.2794)
			(stroke
				(width 0.1)
				(type default)
			)
			(layer "F.Fab")
		)
		(fp_line
			(start 0.67945 0.3048)
			(end 0.120396 0.3048)
			(stroke
				(width 0.1)
				(type default)
			)
			(layer "F.Fab")
		)
		(fp_line
			(start -0.12065 0.2794)
			(end -0.12065 0.3048)
			(stroke
				(width 0.1)
				(type default)
			)
			(layer "F.Fab")
		)
		(fp_line
			(start 0.120396 0.2794)
			(end -0.12065 0.2794)
			(stroke
				(width 0.1)
				(type default)
			)
			(layer "F.Fab")
		)
		(fp_line
			(start -0.12065 -0.2794)
			(end 0.12065 -0.2794)
			(stroke
				(width 0.1)
				(type default)
			)
			(layer "F.Fab")
		)
		(fp_line
			(start 0.12065 -0.2794)
			(end 0.12065 -0.3048)
			(stroke
				(width 0.1)
				(type default)
			)
			(layer "F.Fab")
		)
		(fp_line
			(start 0.12065 -0.3048)
			(end 0.67945 -0.3048)
			(stroke
				(width 0.1)
				(type default)
			)
			(layer "F.Fab")
		)
		(fp_line
			(start 0.67945 -0.3048)
			(end 0.67945 0.3048)
			(stroke
				(width 0.1)
				(type default)
			)
			(layer "F.Fab")
		)
		(fp_line
			(start -0.67945 -0.305054)
			(end -0.12065 -0.305054)
			(stroke
				(width 0.1)
				(type default)
			)
			(layer "F.Fab")
		)
		(fp_line
			(start -0.12065 -0.305054)
			(end -0.12065 -0.2794)
			(stroke
				(width 0.1)
				(type default)
			)
			(layer "F.Fab")
		)
		(pad "1" smd circle
			(at -0.40005 0 270)
			(size 0 0)
			(layers "F.Cu" "F.Mask" "F.Paste")
			(net "GND")
		)
		(pad "2" smd circle
			(at 0.40005 0 270)
			(size 0 0)
			(layers "F.Cu" "F.Mask" "F.Paste")
			(net "P3V3_AUX")
		)
	)
	(footprint ""
		(layer "F.Cu")
		(at 430.276 -40.386 180)
		(property "Reference" "R133"
			(at 0 0 180)
			(layer "F.SilkS")
			(hide yes)
			(effects
				(font
					(size 1.27 1.27)
				)
			)
		)
		(property "Value" ""
			(at 0 0 180)
			(layer "F.Fab")
			(effects
				(font
					(size 1.27 1.27)
				)
			)
		)
		(duplicate_pad_numbers_are_jumpers no)
		(fp_line
			(start 0.7874 0.4064)
			(end -0.7874 0.4064)
			(stroke
				(width 0.1524)
				(type default)
			)
			(layer "F.SilkS")
		)
		(fp_line
			(start 0.7874 -0.4064)
			(end 0.7874 0.4064)
			(stroke
				(width 0.1524)
				(type default)
			)
			(layer "F.SilkS")
		)
		(fp_line
			(start -0.7874 0.4064)
			(end -0.7874 -0.4064)
			(stroke
				(width 0.1524)
				(type default)
			)
			(layer "F.SilkS")
		)
		(fp_line
			(start -0.7874 -0.4064)
			(end 0.7874 -0.4064)
			(stroke
				(width 0.1524)
				(type default)
			)
			(layer "F.SilkS")
		)
		(fp_line
			(start 0.67945 0.3048)
			(end 0.120396 0.3048)
			(stroke
				(width 0.1)
				(type default)
			)
			(layer "F.Fab")
		)
		(fp_line
			(start 0.67945 -0.3048)
			(end 0.67945 0.3048)
			(stroke
				(width 0.1)
				(type default)
			)
			(layer "F.Fab")
		)
		(fp_line
			(start 0.12065 -0.2794)
			(end 0.12065 -0.3048)
			(stroke
				(width 0.1)
				(type default)
			)
			(layer "F.Fab")
		)
		(fp_line
			(start 0.12065 -0.3048)
			(end 0.67945 -0.3048)
			(stroke
				(width 0.1)
				(type default)
			)
			(layer "F.Fab")
		)
		(fp_line
			(start 0.120396 0.3048)
			(end 0.120396 0.2794)
			(stroke
				(width 0.1)
				(type default)
			)
			(layer "F.Fab")
		)
		(fp_line
			(start 0.120396 0.2794)
			(end -0.12065 0.2794)
			(stroke
				(width 0.1)
				(type default)
			)
			(layer "F.Fab")
		)
		(fp_line
			(start -0.12065 0.3048)
			(end -0.67945 0.3048)
			(stroke
				(width 0.1)
				(type default)
			)
			(layer "F.Fab")
		)
		(fp_line
			(start -0.12065 0.2794)
			(end -0.12065 0.3048)
			(stroke
				(width 0.1)
				(type default)
			)
			(layer "F.Fab")
		)
		(fp_line
			(start -0.12065 -0.2794)
			(end 0.12065 -0.2794)
			(stroke
				(width 0.1)
				(type default)
			)
			(layer "F.Fab")
		)
		(fp_line
			(start -0.12065 -0.305054)
			(end -0.12065 -0.2794)
			(stroke
				(width 0.1)
				(type default)
			)
			(layer "F.Fab")
		)
		(fp_line
			(start -0.67945 0.3048)
			(end -0.67945 -0.305054)
			(stroke
				(width 0.1)
				(type default)
			)
			(layer "F.Fab")
		)
		(fp_line
			(start -0.67945 -0.305054)
			(end -0.12065 -0.305054)
			(stroke
				(width 0.1)
				(type default)
			)
			(layer "F.Fab")
		)
		(pad "1" smd circle
			(at -0.40005 0 180)
			(size 0 0)
			(layers "F.Cu" "F.Mask" "F.Paste")
			(net "P3V3_AUX")
		)
		(pad "2" smd circle
			(at 0.40005 0 180)
			(size 0 0)
			(layers "F.Cu" "F.Mask" "F.Paste")
			(net "BOARD_ID_2")
		)
	)
	(footprint ""
		(layer "F.Cu")
		(at 369.000024 -13.499846 180)
		(property "Reference" "H12"
			(at 1.081024 10.476484 0)
			(unlocked yes)
			(layer "F.SilkS")
			(effects
				(font
					(size 0.7874 0.5842)
					(thickness 0.1524)
				)
				(justify left)
			)
		)
		(property "Value" ""
			(at 0 0 180)
			(layer "F.Fab")
			(effects
				(font
					(size 1.27 1.27)
				)
			)
		)
		(duplicate_pad_numbers_are_jumpers no)
		(pad "1" thru_hole oval
			(at 0 0 180)
			(size 9.017 14.0208)
			(drill 3.0226
				(offset 0 2.499868)
			)
			(layers "*.Cu" "*.Mask")
			(remove_unused_layers no)
			(net "GND")
			(clearance -1.500378)
			(padstack
				(mode front_inner_back)
				(layer "Inner"
					(shape circle)
					(size 0 0)
					(clearance 0)
				)
				(layer "B.Cu"
					(shape oval)
					(size 9.017 14.0208)
					(offset 0 2.499868)
					(clearance -1.500378)
				)
			)
		)
	)
)
